# T6G (Grand Teton) — schematic netlist excerpt (pin names and nets, part order shuffled) for the footprints in the layout excerpt that follows; sources: Cadence DE-HDL packaged netlist, KiCad conversion of 04192023_DAF0TMB3IC0_F0TG_MB_C_brd_V02_OCP.brd

PR190  Q_RES  5.6 1% CHIP  pkg 0402LF  page 211 : A = SW_PVDDCR_CPU0_P1_BOOT2 ; B = SW_PVDDCR_CPU0_P1_BOOT2_RC
R707  Q_RES  10K 1% CHIP  pkg 0201LF  page 320 : A = GPIO2_RT_CPU1_P0 ; B = GND
PR524  Q_RES  1.5 1% EMPTY  pkg 0402LF  page 213 : A = SW_PVDDCR_CPU0_P1_SW6_RC ; B = GND

(kicad_pcb
	(version 20260206)
	(generator "pcbnew")
	(generator_version "10.0")
	(general
		(thickness 1.6)
		(legacy_teardrops no)
	)
	(paper "A4")
	(title_block
		(title "04192023_DAF0TMB3IC0_F0TG_MB_C_brd_V02_OCP.brd")
		(comment 1 "Grand Teton / footprints 566-568 of 8354")
	)
	(layers
		(0 "F.Cu" signal "TOP")
		(4 "In1.Cu" signal "GND")
		(6 "In2.Cu" signal "IN1")
		(8 "In3.Cu" signal "GND1")
		(10 "In4.Cu" signal "IN2")
		(12 "In5.Cu" signal "GND2")
		(14 "In6.Cu" signal "IN3")
		(16 "In7.Cu" signal "GND3")
		(18 "In8.Cu" signal "VCC")
		(20 "In9.Cu" signal "VCC1")
		(22 "In10.Cu" signal "GND4")
		(24 "In11.Cu" signal "IN4")
		(26 "In12.Cu" signal "GND5")
		(28 "In13.Cu" signal "IN5")
		(30 "In14.Cu" signal "GND6")
		(32 "In15.Cu" signal "IN6")
		(34 "In16.Cu" signal "GND7")
		(2 "B.Cu" signal "BOTTOM")
		(9 "F.Adhes" user "F.Adhesive")
		(11 "B.Adhes" user "B.Adhesive")
		(13 "F.Paste" user "Package Geometry/Pastemask Top")
		(15 "B.Paste" user "Package Geometry/Pastemask Bottom")
		(5 "F.SilkS" user "Ref Des/Silkscreen Top")
		(7 "B.SilkS" user "Ref Des/Silkscreen Bottom")
		(1 "F.Mask" user "Board Geometry/Soldermask Top")
		(3 "B.Mask" user "Board Geometry/Soldermask Bottom")
		(17 "Dwgs.User" user "User.Drawings")
		(19 "Cmts.User" user "User.Comments")
		(21 "Eco1.User" user "User.Eco1")
		(23 "Eco2.User" user "User.Eco2")
		(25 "Edge.Cuts" user "Board Geometry/Outline")
		(27 "Margin" user)
		(31 "F.CrtYd" user "Package Geometry/Place Bound Top")
		(29 "B.CrtYd" user "Package Geometry/Place Bound Bottom")
		(35 "F.Fab" user "Ref Des/Assembly Top")
		(33 "B.Fab" user "Ref Des/Assembly Bottom")
	)
	(footprint ""
		(layer "F.Cu")
		(at 43.265852 -385.58216)
		(property "Reference" "R707"
			(at 0 0 0)
			(layer "F.SilkS")
			(hide yes)
			(effects
				(font
					(size 1.27 1.27)
				)
			)
		)
		(property "Value" ""
			(at 0 0 0)
			(layer "F.Fab")
			(effects
				(font
					(size 1.27 1.27)
				)
			)
		)
		(duplicate_pad_numbers_are_jumpers no)
		(fp_line
			(start -0.32512 -0.175006)
			(end 0.32512 -0.175006)
			(stroke
				(width 0.1)
				(type default)
			)
			(layer "F.Fab")
		)
		(fp_line
			(start -0.32512 0.175006)
			(end -0.32512 -0.175006)
			(stroke
				(width 0.1)
				(type default)
			)
			(layer "F.Fab")
		)
		(fp_line
			(start 0.32512 -0.175006)
			(end 0.32512 0.175006)
			(stroke
				(width 0.1)
				(type default)
			)
			(layer "F.Fab")
		)
		(fp_line
			(start 0.32512 0.175006)
			(end -0.32512 0.175006)
			(stroke
				(width 0.1)
				(type default)
			)
			(layer "F.Fab")
		)
		(pad "1" smd rect
			(at -0.2667 0)
			(size 0.3048 0.381)
			(layers "F.Cu" "F.Mask" "F.Paste")
			(net "GPIO2_RT_CPU1_P0")
		)
		(pad "2" smd rect
			(at 0.2667 0 180)
			(size 0.3048 0.381)
			(layers "F.Cu" "F.Mask" "F.Paste")
			(net "GND")
		)
	)
	(footprint ""
		(layer "F.Cu")
		(at 89.922604 -178.024028 -90)
		(property "Reference" "PR190"
			(at 0 0 270)
			(layer "F.SilkS")
			(hide yes)
			(effects
				(font
					(size 1.27 1.27)
				)
			)
		)
		(property "Value" ""
			(at 0 0 270)
			(layer "F.Fab")
			(effects
				(font
					(size 1.27 1.27)
				)
			)
		)
		(duplicate_pad_numbers_are_jumpers no)
		(fp_line
			(start -0.7874 0.4064)
			(end -0.7874 -0.4064)
			(stroke
				(width 0.1524)
				(type default)
			)
			(layer "F.SilkS")
		)
		(fp_line
			(start 0.7874 0.4064)
			(end -0.7874 0.4064)
			(stroke
				(width 0.1524)
				(type default)
			)
			(layer "F.SilkS")
		)
		(fp_line
			(start -0.7874 -0.4064)
			(end 0.7874 -0.4064)
			(stroke
				(width 0.1524)
				(type default)
			)
			(layer "F.SilkS")
		)
		(fp_line
			(start 0.7874 -0.4064)
			(end 0.7874 0.4064)
			(stroke
				(width 0.1524)
				(type default)
			)
			(layer "F.SilkS")
		)
		(fp_line
			(start -0.67945 0.3048)
			(end -0.67945 -0.305054)
			(stroke
				(width 0.1)
				(type default)
			)
			(layer "F.Fab")
		)
		(fp_line
			(start -0.12065 0.3048)
			(end -0.67945 0.3048)
			(stroke
				(width 0.1)
				(type default)
			)
			(layer "F.Fab")
		)
		(fp_line
			(start 0.120396 0.3048)
			(end 0.120396 0.2794)
			(stroke
				(width 0.1)
				(type default)
			)
			(layer "F.Fab")
		)
		(fp_line
			(start 0.67945 0.3048)
			(end 0.120396 0.3048)
			(stroke
				(width 0.1)
				(type default)
			)
			(layer "F.Fab")
		)
		(fp_line
			(start -0.12065 0.2794)
			(end -0.12065 0.3048)
			(stroke
				(width 0.1)
				(type default)
			)
			(layer "F.Fab")
		)
		(fp_line
			(start 0.120396 0.2794)
			(end -0.12065 0.2794)
			(stroke
				(width 0.1)
				(type default)
			)
			(layer "F.Fab")
		)
		(fp_line
			(start -0.12065 -0.2794)
			(end 0.12065 -0.2794)
			(stroke
				(width 0.1)
				(type default)
			)
			(layer "F.Fab")
		)
		(fp_line
			(start 0.12065 -0.2794)
			(end 0.12065 -0.3048)
			(stroke
				(width 0.1)
				(type default)
			)
			(layer "F.Fab")
		)
		(fp_line
			(start 0.12065 -0.3048)
			(end 0.67945 -0.3048)
			(stroke
				(width 0.1)
				(type default)
			)
			(layer "F.Fab")
		)
		(fp_line
			(start 0.67945 -0.3048)
			(end 0.67945 0.3048)
			(stroke
				(width 0.1)
				(type default)
			)
			(layer "F.Fab")
		)
		(fp_line
			(start -0.67945 -0.305054)
			(end -0.12065 -0.305054)
			(stroke
				(width 0.1)
				(type default)
			)
			(layer "F.Fab")
		)
		(fp_line
			(start -0.12065 -0.305054)
			(end -0.12065 -0.2794)
			(stroke
				(width 0.1)
				(type default)
			)
			(layer "F.Fab")
		)
		(pad "1" smd circle
			(at -0.40005 0 270)
			(size 0 0)
			(layers "F.Cu" "F.Mask" "F.Paste")
			(net "SW_PVDDCR_CPU0_P1_BOOT2")
		)
		(pad "2" smd circle
			(at 0.40005 0 270)
			(size 0 0)
			(layers "F.Cu" "F.Mask" "F.Paste")
			(net "SW_PVDDCR_CPU0_P1_BOOT2_RC")
		)
	)
	(footprint ""
		(layer "F.Cu")
		(at 69.324728 -170.662854 -90)
		(property "Reference" "PR524"
			(at 0 0 270)
			(layer "F.SilkS")
			(hide yes)
			(effects
				(font
					(size 1.27 1.27)
				)
			)
		)
		(property "Value" ""
			(at 0 0 270)
			(layer "F.Fab")
			(effects
				(font
					(size 1.27 1.27)
				)
			)
		)
		(duplicate_pad_numbers_are_jumpers no)
		(fp_line
			(start -0.7874 0.4064)
			(end -0.7874 -0.4064)
			(stroke
				(width 0.1524)
				(type default)
			)
			(layer "F.SilkS")
		)
		(fp_line
			(start 0.7874 0.4064)
			(end -0.7874 0.4064)
			(stroke
				(width 0.1524)
				(type default)
			)
			(layer "F.SilkS")
		)
		(fp_line
			(start -0.7874 -0.4064)
			(end 0.7874 -0.4064)
			(stroke
				(width 0.1524)
				(type default)
			)
			(layer "F.SilkS")
		)
		(fp_line
			(start 0.7874 -0.4064)
			(end 0.7874 0.4064)
			(stroke
				(width 0.1524)
				(type default)
			)
			(layer "F.SilkS")
		)
		(fp_line
			(start -0.67945 0.3048)
			(end -0.67945 -0.305054)
			(stroke
				(width 0.1)
				(type default)
			)
			(layer "F.Fab")
		)
		(fp_line
			(start -0.12065 0.3048)
			(end -0.67945 0.3048)
			(stroke
				(width 0.1)
				(type default)
			)
			(layer "F.Fab")
		)
		(fp_line
			(start 0.120396 0.3048)
			(end 0.120396 0.2794)
			(stroke
				(width 0.1)
				(type default)
			)
			(layer "F.Fab")
		)
		(fp_line
			(start 0.67945 0.3048)
			(end 0.120396 0.3048)
			(stroke
				(width 0.1)
				(type default)
			)
			(layer "F.Fab")
		)
		(fp_line
			(start -0.12065 0.2794)
			(end -0.12065 0.3048)
			(stroke
				(width 0.1)
				(type default)
			)
			(layer "F.Fab")
		)
		(fp_line
			(start 0.120396 0.2794)
			(end -0.12065 0.2794)
			(stroke
				(width 0.1)
				(type default)
			)
			(layer "F.Fab")
		)
		(fp_line
			(start -0.12065 -0.2794)
			(end 0.12065 -0.2794)
			(stroke
				(width 0.1)
				(type default)
			)
			(layer "F.Fab")
		)
		(fp_line
			(start 0.12065 -0.2794)
			(end 0.12065 -0.3048)
			(stroke
				(width 0.1)
				(type default)
			)
			(layer "F.Fab")
		)
		(fp_line
			(start 0.12065 -0.3048)
			(end 0.67945 -0.3048)
			(stroke
				(width 0.1)
				(type default)
			)
			(layer "F.Fab")
		)
		(fp_line
			(start 0.67945 -0.3048)
			(end 0.67945 0.3048)
			(stroke
				(width 0.1)
				(type default)
			)
			(layer "F.Fab")
		)
		(fp_line
			(start -0.67945 -0.305054)
			(end -0.12065 -0.305054)
			(stroke
				(width 0.1)
				(type default)
			)
			(layer "F.Fab")
		)
		(fp_line
			(start -0.12065 -0.305054)
			(end -0.12065 -0.2794)
			(stroke
				(width 0.1)
				(type default)
			)
			(layer "F.Fab")
		)
		(pad "1" smd circle
			(at -0.40005 0 270)
			(size 0 0)
			(layers "F.Cu" "F.Mask" "F.Paste")
			(net "SW_PVDDCR_CPU0_P1_SW6_RC")
		)
		(pad "2" smd circle
			(at 0.40005 0 270)
			(size 0 0)
			(layers "F.Cu" "F.Mask" "F.Paste")
			(net "GND")
		)
	)
)
